(kicad_pcb
	(version 20260206)
	(generator "pcbnew")
	(generator_version "10.0")
	(general
		(thickness 1.6)
		(legacy_teardrops no)
	)
	(paper "A4")
	(title_block
		(title "01162023_DA0F0TEBIF0_F0T_Expander_BD_F_brd_V02_OCP.brd")
		(comment 1 "Grand Teton / footprints 830-836 of 9728")
	)
	(layers
		(0 "F.Cu" signal "TOP")
		(4 "In1.Cu" signal "GND")
		(6 "In2.Cu" signal "VCC")
		(8 "In3.Cu" signal "VCC1")
		(10 "In4.Cu" signal "GND1")
		(12 "In5.Cu" signal "IN1")
		(14 "In6.Cu" signal "GND2")
		(16 "In7.Cu" signal "IN2")
		(18 "In8.Cu" signal "GND3")
		(20 "In9.Cu" signal "IN3")
		(22 "In10.Cu" signal "GND4")
		(24 "In11.Cu" signal "IN4")
		(26 "In12.Cu" signal "GND5")
		(28 "In13.Cu" signal "IN5")
		(30 "In14.Cu" signal "GND6")
		(32 "In15.Cu" signal "IN6")
		(34 "In16.Cu" signal "GND7")
		(2 "B.Cu" signal "BOTTOM")
		(9 "F.Adhes" user "F.Adhesive")
		(11 "B.Adhes" user "B.Adhesive")
		(13 "F.Paste" user "Package Geometry/Pastemask Top")
		(15 "B.Paste" user "Package Geometry/Pastemask Bottom")
		(5 "F.SilkS" user "Ref Des/Silkscreen Top")
		(7 "B.SilkS" user "Ref Des/Silkscreen Bottom")
		(1 "F.Mask" user "Board Geometry/Soldermask Top")
		(3 "B.Mask" user "Board Geometry/Soldermask Bottom")
		(17 "Dwgs.User" user "User.Drawings")
		(19 "Cmts.User" user "User.Comments")
		(21 "Eco1.User" user "User.Eco1")
		(23 "Eco2.User" user "User.Eco2")
		(25 "Edge.Cuts" user "Board Geometry/Outline")
		(27 "Margin" user)
		(31 "F.CrtYd" user "Package Geometry/Place Bound Top")
		(29 "B.CrtYd" user "Package Geometry/Place Bound Bottom")
		(35 "F.Fab" user "Ref Des/Assembly Top")
		(33 "B.Fab" user "Ref Des/Assembly Bottom")
	)
	(footprint ""
		(layer "F.Cu")
		(at 373.092726 -257.148838 -90)
		(property "Reference" "R1463"
			(at 0 0 270)
			(layer "F.SilkS")
			(hide yes)
			(effects
				(font
					(size 1.27 1.27)
				)
			)
		)
		(property "Value" ""
			(at 0 0 270)
			(layer "F.Fab")
			(effects
				(font
					(size 1.27 1.27)
				)
			)
		)
		(duplicate_pad_numbers_are_jumpers no)
		(fp_line
			(start -0.7874 0.4064)
			(end -0.7874 -0.4064)
			(stroke
				(width 0.1524)
				(type default)
			)
			(layer "F.SilkS")
		)
		(fp_line
			(start 0.7874 0.4064)
			(end -0.7874 0.4064)
			(stroke
				(width 0.1524)
				(type default)
			)
			(layer "F.SilkS")
		)
		(fp_line
			(start -0.7874 -0.4064)
			(end 0.7874 -0.4064)
			(stroke
				(width 0.1524)
				(type default)
			)
			(layer "F.SilkS")
		)
		(fp_line
			(start 0.7874 -0.4064)
			(end 0.7874 0.4064)
			(stroke
				(width 0.1524)
				(type default)
			)
			(layer "F.SilkS")
		)
		(fp_line
			(start -0.67945 0.3048)
			(end -0.67945 -0.305054)
			(stroke
				(width 0.1)
				(type default)
			)
			(layer "F.Fab")
		)
		(fp_line
			(start -0.12065 0.3048)
			(end -0.67945 0.3048)
			(stroke
				(width 0.1)
				(type default)
			)
			(layer "F.Fab")
		)
		(fp_line
			(start 0.120396 0.3048)
			(end 0.120396 0.2794)
			(stroke
				(width 0.1)
				(type default)
			)
			(layer "F.Fab")
		)
		(fp_line
			(start 0.67945 0.3048)
			(end 0.120396 0.3048)
			(stroke
				(width 0.1)
				(type default)
			)
			(layer "F.Fab")
		)
		(fp_line
			(start -0.12065 0.2794)
			(end -0.12065 0.3048)
			(stroke
				(width 0.1)
				(type default)
			)
			(layer "F.Fab")
		)
		(fp_line
			(start 0.120396 0.2794)
			(end -0.12065 0.2794)
			(stroke
				(width 0.1)
				(type default)
			)
			(layer "F.Fab")
		)
		(fp_line
			(start -0.12065 -0.2794)
			(end 0.12065 -0.2794)
			(stroke
				(width 0.1)
				(type default)
			)
			(layer "F.Fab")
		)
		(fp_line
			(start 0.12065 -0.2794)
			(end 0.12065 -0.3048)
			(stroke
				(width 0.1)
				(type default)
			)
			(layer "F.Fab")
		)
		(fp_line
			(start 0.12065 -0.3048)
			(end 0.67945 -0.3048)
			(stroke
				(width 0.1)
				(type default)
			)
			(layer "F.Fab")
		)
		(fp_line
			(start 0.67945 -0.3048)
			(end 0.67945 0.3048)
			(stroke
				(width 0.1)
				(type default)
			)
			(layer "F.Fab")
		)
		(fp_line
			(start -0.67945 -0.305054)
			(end -0.12065 -0.305054)
			(stroke
				(width 0.1)
				(type default)
			)
			(layer "F.Fab")
		)
		(fp_line
			(start -0.12065 -0.305054)
			(end -0.12065 -0.2794)
			(stroke
				(width 0.1)
				(type default)
			)
			(layer "F.Fab")
		)
		(pad "1" smd circle
			(at -0.40005 0 270)
			(size 0 0)
			(layers "F.Cu" "F.Mask" "F.Paste")
			(net "P3V3_LED")
		)
		(pad "2" smd circle
			(at 0.40005 0 270)
			(size 0 0)
			(layers "F.Cu" "F.Mask" "F.Paste")
			(net "LED_PEX3_SYS_ERR_N")
		)
	)
	(footprint ""
		(layer "F.Cu")
		(at 384.938524 -130.408934)
		(property "Reference" "C672"
			(at 0 0 0)
			(layer "F.SilkS")
			(hide yes)
			(effects
				(font
					(size 1.27 1.27)
				)
			)
		)
		(property "Value" ""
			(at 0 0 0)
			(layer "F.Fab")
			(effects
				(font
					(size 1.27 1.27)
				)
			)
		)
		(duplicate_pad_numbers_are_jumpers no)
		(fp_line
			(start -0.299974 -0.150114)
			(end 0.299974 -0.150114)
			(stroke
				(width 0.1)
				(type default)
			)
			(layer "F.Fab")
		)
		(fp_line
			(start -0.299974 0.150114)
			(end -0.299974 -0.150114)
			(stroke
				(width 0.1)
				(type default)
			)
			(layer "F.Fab")
		)
		(fp_line
			(start 0.299974 -0.150114)
			(end 0.299974 0.150114)
			(stroke
				(width 0.1)
				(type default)
			)
			(layer "F.Fab")
		)
		(fp_line
			(start 0.299974 0.150114)
			(end -0.299974 0.150114)
			(stroke
				(width 0.1)
				(type default)
			)
			(layer "F.Fab")
		)
		(pad "1" smd rect
			(at -0.2667 0)
			(size 0.3048 0.381)
			(layers "F.Cu" "F.Mask" "F.Paste")
			(net "P5E_PEX3_STN1_TX_DP<28>")
		)
		(pad "2" smd rect
			(at 0.2667 0)
			(size 0.3048 0.381)
			(layers "F.Cu" "F.Mask" "F.Paste")
			(net "P5E_PEX3_STN1_TX_C_DP<28>")
		)
	)
	(footprint ""
		(layer "F.Cu")
		(at 227.743512 -231.416606 -90)
		(property "Reference" "R4539"
			(at 0 0 270)
			(layer "F.SilkS")
			(hide yes)
			(effects
				(font
					(size 1.27 1.27)
				)
			)
		)
		(property "Value" ""
			(at 0 0 270)
			(layer "F.Fab")
			(effects
				(font
					(size 1.27 1.27)
				)
			)
		)
		(duplicate_pad_numbers_are_jumpers no)
		(fp_line
			(start -0.7874 0.4064)
			(end -0.7874 -0.4064)
			(stroke
				(width 0.1524)
				(type default)
			)
			(layer "F.SilkS")
		)
		(fp_line
			(start 0.7874 0.4064)
			(end -0.7874 0.4064)
			(stroke
				(width 0.1524)
				(type default)
			)
			(layer "F.SilkS")
		)
		(fp_line
			(start -0.7874 -0.4064)
			(end 0.7874 -0.4064)
			(stroke
				(width 0.1524)
				(type default)
			)
			(layer "F.SilkS")
		)
		(fp_line
			(start 0.7874 -0.4064)
			(end 0.7874 0.4064)
			(stroke
				(width 0.1524)
				(type default)
			)
			(layer "F.SilkS")
		)
		(fp_line
			(start -0.67945 0.3048)
			(end -0.67945 -0.305054)
			(stroke
				(width 0.1)
				(type default)
			)
			(layer "F.Fab")
		)
		(fp_line
			(start -0.12065 0.3048)
			(end -0.67945 0.3048)
			(stroke
				(width 0.1)
				(type default)
			)
			(layer "F.Fab")
		)
		(fp_line
			(start 0.120396 0.3048)
			(end 0.120396 0.2794)
			(stroke
				(width 0.1)
				(type default)
			)
			(layer "F.Fab")
		)
		(fp_line
			(start 0.67945 0.3048)
			(end 0.120396 0.3048)
			(stroke
				(width 0.1)
				(type default)
			)
			(layer "F.Fab")
		)
		(fp_line
			(start -0.12065 0.2794)
			(end -0.12065 0.3048)
			(stroke
				(width 0.1)
				(type default)
			)
			(layer "F.Fab")
		)
		(fp_line
			(start 0.120396 0.2794)
			(end -0.12065 0.2794)
			(stroke
				(width 0.1)
				(type default)
			)
			(layer "F.Fab")
		)
		(fp_line
			(start -0.12065 -0.2794)
			(end 0.12065 -0.2794)
			(stroke
				(width 0.1)
				(type default)
			)
			(layer "F.Fab")
		)
		(fp_line
			(start 0.12065 -0.2794)
			(end 0.12065 -0.3048)
			(stroke
				(width 0.1)
				(type default)
			)
			(layer "F.Fab")
		)
		(fp_line
			(start 0.12065 -0.3048)
			(end 0.67945 -0.3048)
			(stroke
				(width 0.1)
				(type default)
			)
			(layer "F.Fab")
		)
		(fp_line
			(start 0.67945 -0.3048)
			(end 0.67945 0.3048)
			(stroke
				(width 0.1)
				(type default)
			)
			(layer "F.Fab")
		)
		(fp_line
			(start -0.67945 -0.305054)
			(end -0.12065 -0.305054)
			(stroke
				(width 0.1)
				(type default)
			)
			(layer "F.Fab")
		)
		(fp_line
			(start -0.12065 -0.305054)
			(end -0.12065 -0.2794)
			(stroke
				(width 0.1)
				(type default)
			)
			(layer "F.Fab")
		)
		(pad "1" smd circle
			(at -0.40005 0 270)
			(size 0 0)
			(layers "F.Cu" "F.Mask" "F.Paste")
			(net "NIC3_MAIN_PWR_BIC_EN_R")
		)
		(pad "2" smd circle
			(at 0.40005 0 270)
			(size 0 0)
			(layers "F.Cu" "F.Mask" "F.Paste")
			(net "NIC3_MAIN_PWR_BIC_EN")
		)
	)
	(footprint ""
		(layer "F.Cu")
		(at 204.591158 -87.977472)
		(property "Reference" "R4261"
			(at 0 0 0)
			(layer "F.SilkS")
			(hide yes)
			(effects
				(font
					(size 1.27 1.27)
				)
			)
		)
		(property "Value" ""
			(at 0 0 0)
			(layer "F.Fab")
			(effects
				(font
					(size 1.27 1.27)
				)
			)
		)
		(duplicate_pad_numbers_are_jumpers no)
		(fp_line
			(start -0.7874 -0.4064)
			(end 0.7874 -0.4064)
			(stroke
				(width 0.1524)
				(type default)
			)
			(layer "F.SilkS")
		)
		(fp_line
			(start -0.7874 0.4064)
			(end -0.7874 -0.4064)
			(stroke
				(width 0.1524)
				(type default)
			)
			(layer "F.SilkS")
		)
		(fp_line
			(start 0.7874 -0.4064)
			(end 0.7874 0.4064)
			(stroke
				(width 0.1524)
				(type default)
			)
			(layer "F.SilkS")
		)
		(fp_line
			(start 0.7874 0.4064)
			(end -0.7874 0.4064)
			(stroke
				(width 0.1524)
				(type default)
			)
			(layer "F.SilkS")
		)
		(fp_line
			(start -0.67945 -0.305054)
			(end -0.12065 -0.305054)
			(stroke
				(width 0.1)
				(type default)
			)
			(layer "F.Fab")
		)
		(fp_line
			(start -0.67945 0.3048)
			(end -0.67945 -0.305054)
			(stroke
				(width 0.1)
				(type default)
			)
			(layer "F.Fab")
		)
		(fp_line
			(start -0.12065 -0.305054)
			(end -0.12065 -0.2794)
			(stroke
				(width 0.1)
				(type default)
			)
			(layer "F.Fab")
		)
		(fp_line
			(start -0.12065 -0.2794)
			(end 0.12065 -0.2794)
			(stroke
				(width 0.1)
				(type default)
			)
			(layer "F.Fab")
		)
		(fp_line
			(start -0.12065 0.2794)
			(end -0.12065 0.3048)
			(stroke
				(width 0.1)
				(type default)
			)
			(layer "F.Fab")
		)
		(fp_line
			(start -0.12065 0.3048)
			(end -0.67945 0.3048)
			(stroke
				(width 0.1)
				(type default)
			)
			(layer "F.Fab")
		)
		(fp_line
			(start 0.120396 0.2794)
			(end -0.12065 0.2794)
			(stroke
				(width 0.1)
				(type default)
			)
			(layer "F.Fab")
		)
		(fp_line
			(start 0.120396 0.3048)
			(end 0.120396 0.2794)
			(stroke
				(width 0.1)
				(type default)
			)
			(layer "F.Fab")
		)
		(fp_line
			(start 0.12065 -0.3048)
			(end 0.67945 -0.3048)
			(stroke
				(width 0.1)
				(type default)
			)
			(layer "F.Fab")
		)
		(fp_line
			(start 0.12065 -0.2794)
			(end 0.12065 -0.3048)
			(stroke
				(width 0.1)
				(type default)
			)
			(layer "F.Fab")
		)
		(fp_line
			(start 0.67945 -0.3048)
			(end 0.67945 0.3048)
			(stroke
				(width 0.1)
				(type default)
			)
			(layer "F.Fab")
		)
		(fp_line
			(start 0.67945 0.3048)
			(end 0.120396 0.3048)
			(stroke
				(width 0.1)
				(type default)
			)
			(layer "F.Fab")
		)
		(pad "1" smd circle
			(at -0.40005 0)
			(size 0 0)
			(layers "F.Cu" "F.Mask" "F.Paste")
			(net "P3V3_AUX")
		)
		(pad "2" smd circle
			(at 0.40005 0)
			(size 0 0)
			(layers "F.Cu" "F.Mask" "F.Paste")
			(net "SSD_LED_IOEXP_A1")
		)
	)
	(footprint ""
		(layer "F.Cu")
		(at 364.659672 -146.642328 -90)
		(property "Reference" "C946"
			(at 0 0 270)
			(layer "F.SilkS")
			(hide yes)
			(effects
				(font
					(size 1.27 1.27)
				)
			)
		)
		(property "Value" ""
			(at 0 0 270)
			(layer "F.Fab")
			(effects
				(font
					(size 1.27 1.27)
				)
			)
		)
		(duplicate_pad_numbers_are_jumpers no)
		(fp_line
			(start -0.7874 0.4064)
			(end -0.7874 -0.4064)
			(stroke
				(width 0.1524)
				(type default)
			)
			(layer "F.SilkS")
		)
		(fp_line
			(start 0.7874 0.4064)
			(end -0.7874 0.4064)
			(stroke
				(width 0.1524)
				(type default)
			)
			(layer "F.SilkS")
		)
		(fp_line
			(start -0.7874 -0.4064)
			(end 0.7874 -0.4064)
			(stroke
				(width 0.1524)
				(type default)
			)
			(layer "F.SilkS")
		)
		(fp_line
			(start 0.7874 -0.4064)
			(end 0.7874 0.4064)
			(stroke
				(width 0.1524)
				(type default)
			)
			(layer "F.SilkS")
		)
		(fp_line
			(start -0.67945 0.3048)
			(end -0.67945 -0.305054)
			(stroke
				(width 0.1)
				(type default)
			)
			(layer "F.Fab")
		)
		(fp_line
			(start -0.12065 0.3048)
			(end -0.67945 0.3048)
			(stroke
				(width 0.1)
				(type default)
			)
			(layer "F.Fab")
		)
		(fp_line
			(start 0.120396 0.3048)
			(end 0.120396 0.2794)
			(stroke
				(width 0.1)
				(type default)
			)
			(layer "F.Fab")
		)
		(fp_line
			(start 0.67945 0.3048)
			(end 0.120396 0.3048)
			(stroke
				(width 0.1)
				(type default)
			)
			(layer "F.Fab")
		)
		(fp_line
			(start -0.12065 0.2794)
			(end -0.12065 0.3048)
			(stroke
				(width 0.1)
				(type default)
			)
			(layer "F.Fab")
		)
		(fp_line
			(start 0.120396 0.2794)
			(end -0.12065 0.2794)
			(stroke
				(width 0.1)
				(type default)
			)
			(layer "F.Fab")
		)
		(fp_line
			(start -0.12065 -0.2794)
			(end 0.12065 -0.2794)
			(stroke
				(width 0.1)
				(type default)
			)
			(layer "F.Fab")
		)
		(fp_line
			(start 0.12065 -0.2794)
			(end 0.12065 -0.3048)
			(stroke
				(width 0.1)
				(type default)
			)
			(layer "F.Fab")
		)
		(fp_line
			(start 0.12065 -0.3048)
			(end 0.67945 -0.3048)
			(stroke
				(width 0.1)
				(type default)
			)
			(layer "F.Fab")
		)
		(fp_line
			(start 0.67945 -0.3048)
			(end 0.67945 0.3048)
			(stroke
				(width 0.1)
				(type default)
			)
			(layer "F.Fab")
		)
		(fp_line
			(start -0.67945 -0.305054)
			(end -0.12065 -0.305054)
			(stroke
				(width 0.1)
				(type default)
			)
			(layer "F.Fab")
		)
		(fp_line
			(start -0.12065 -0.305054)
			(end -0.12065 -0.2794)
			(stroke
				(width 0.1)
				(type default)
			)
			(layer "F.Fab")
		)
		(pad "1" smd circle
			(at -0.40005 0 270)
			(size 0 0)
			(layers "F.Cu" "F.Mask" "F.Paste")
			(net "P3V3_AUX")
		)
		(pad "2" smd circle
			(at 0.40005 0 270)
			(size 0 0)
			(layers "F.Cu" "F.Mask" "F.Paste")
			(net "GND")
		)
	)
	(footprint ""
		(layer "F.Cu")
		(at 10.3378 -276.389084 90)
		(property "Reference" "C626"
			(at 0 0 90)
			(layer "F.SilkS")
			(hide yes)
			(effects
				(font
					(size 1.27 1.27)
				)
			)
		)
		(property "Value" ""
			(at 0 0 90)
			(layer "F.Fab")
			(effects
				(font
					(size 1.27 1.27)
				)
			)
		)
		(duplicate_pad_numbers_are_jumpers no)
		(fp_line
			(start 0.7874 -0.4064)
			(end 0.7874 0.4064)
			(stroke
				(width 0.1524)
				(type default)
			)
			(layer "F.SilkS")
		)
		(fp_line
			(start -0.7874 -0.4064)
			(end 0.7874 -0.4064)
			(stroke
				(width 0.1524)
				(type default)
			)
			(layer "F.SilkS")
		)
		(fp_line
			(start 0.7874 0.4064)
			(end -0.7874 0.4064)
			(stroke
				(width 0.1524)
				(type default)
			)
			(layer "F.SilkS")
		)
		(fp_line
			(start -0.7874 0.4064)
			(end -0.7874 -0.4064)
			(stroke
				(width 0.1524)
				(type default)
			)
			(layer "F.SilkS")
		)
		(fp_line
			(start -0.12065 -0.305054)
			(end -0.12065 -0.2794)
			(stroke
				(width 0.1)
				(type default)
			)
			(layer "F.Fab")
		)
		(fp_line
			(start -0.67945 -0.305054)
			(end -0.12065 -0.305054)
			(stroke
				(width 0.1)
				(type default)
			)
			(layer "F.Fab")
		)
		(fp_line
			(start 0.67945 -0.3048)
			(end 0.67945 0.3048)
			(stroke
				(width 0.1)
				(type default)
			)
			(layer "F.Fab")
		)
		(fp_line
			(start 0.12065 -0.3048)
			(end 0.67945 -0.3048)
			(stroke
				(width 0.1)
				(type default)
			)
			(layer "F.Fab")
		)
		(fp_line
			(start 0.12065 -0.2794)
			(end 0.12065 -0.3048)
			(stroke
				(width 0.1)
				(type default)
			)
			(layer "F.Fab")
		)
		(fp_line
			(start -0.12065 -0.2794)
			(end 0.12065 -0.2794)
			(stroke
				(width 0.1)
				(type default)
			)
			(layer "F.Fab")
		)
		(fp_line
			(start 0.120396 0.2794)
			(end -0.12065 0.2794)
			(stroke
				(width 0.1)
				(type default)
			)
			(layer "F.Fab")
		)
		(fp_line
			(start -0.12065 0.2794)
			(end -0.12065 0.3048)
			(stroke
				(width 0.1)
				(type default)
			)
			(layer "F.Fab")
		)
		(fp_line
			(start 0.67945 0.3048)
			(end 0.120396 0.3048)
			(stroke
				(width 0.1)
				(type default)
			)
			(layer "F.Fab")
		)
		(fp_line
			(start 0.120396 0.3048)
			(end 0.120396 0.2794)
			(stroke
				(width 0.1)
				(type default)
			)
			(layer "F.Fab")
		)
		(fp_line
			(start -0.12065 0.3048)
			(end -0.67945 0.3048)
			(stroke
				(width 0.1)
				(type default)
			)
			(layer "F.Fab")
		)
		(fp_line
			(start -0.67945 0.3048)
			(end -0.67945 -0.305054)
			(stroke
				(width 0.1)
				(type default)
			)
			(layer "F.Fab")
		)
		(pad "1" smd circle
			(at -0.40005 0 90)
			(size 0 0)
			(layers "F.Cu" "F.Mask" "F.Paste")
			(net "P1V25_PEX0_R")
		)
		(pad "2" smd circle
			(at 0.40005 0 90)
			(size 0 0)
			(layers "F.Cu" "F.Mask" "F.Paste")
			(net "GND")
		)
	)
	(footprint ""
		(layer "F.Cu")
		(at 26.267156 -57.332626)
		(property "Reference" "R6841"
			(at 0 0 0)
			(layer "F.SilkS")
			(hide yes)
			(effects
				(font
					(size 1.27 1.27)
				)
			)
		)
		(property "Value" ""
			(at 0 0 0)
			(layer "F.Fab")
			(effects
				(font
					(size 1.27 1.27)
				)
			)
		)
		(duplicate_pad_numbers_are_jumpers no)
		(fp_line
			(start -0.7874 -0.4064)
			(end 0.7874 -0.4064)
			(stroke
				(width 0.1524)
				(type default)
			)
			(layer "F.SilkS")
		)
		(fp_line
			(start -0.7874 0.4064)
			(end -0.7874 -0.4064)
			(stroke
				(width 0.1524)
				(type default)
			)
			(layer "F.SilkS")
		)
		(fp_line
			(start 0.7874 -0.4064)
			(end 0.7874 0.4064)
			(stroke
				(width 0.1524)
				(type default)
			)
			(layer "F.SilkS")
		)
		(fp_line
			(start 0.7874 0.4064)
			(end -0.7874 0.4064)
			(stroke
				(width 0.1524)
				(type default)
			)
			(layer "F.SilkS")
		)
		(fp_line
			(start -0.67945 -0.305054)
			(end -0.12065 -0.305054)
			(stroke
				(width 0.1)
				(type default)
			)
			(layer "F.Fab")
		)
		(fp_line
			(start -0.67945 0.3048)
			(end -0.67945 -0.305054)
			(stroke
				(width 0.1)
				(type default)
			)
			(layer "F.Fab")
		)
		(fp_line
			(start -0.12065 -0.305054)
			(end -0.12065 -0.2794)
			(stroke
				(width 0.1)
				(type default)
			)
			(layer "F.Fab")
		)
		(fp_line
			(start -0.12065 -0.2794)
			(end 0.12065 -0.2794)
			(stroke
				(width 0.1)
				(type default)
			)
			(layer "F.Fab")
		)
		(fp_line
			(start -0.12065 0.2794)
			(end -0.12065 0.3048)
			(stroke
				(width 0.1)
				(type default)
			)
			(layer "F.Fab")
		)
		(fp_line
			(start -0.12065 0.3048)
			(end -0.67945 0.3048)
			(stroke
				(width 0.1)
				(type default)
			)
			(layer "F.Fab")
		)
		(fp_line
			(start 0.120396 0.2794)
			(end -0.12065 0.2794)
			(stroke
				(width 0.1)
				(type default)
			)
			(layer "F.Fab")
		)
		(fp_line
			(start 0.120396 0.3048)
			(end 0.120396 0.2794)
			(stroke
				(width 0.1)
				(type default)
			)
			(layer "F.Fab")
		)
		(fp_line
			(start 0.12065 -0.3048)
			(end 0.67945 -0.3048)
			(stroke
				(width 0.1)
				(type default)
			)
			(layer "F.Fab")
		)
		(fp_line
			(start 0.12065 -0.2794)
			(end 0.12065 -0.3048)
			(stroke
				(width 0.1)
				(type default)
			)
			(layer "F.Fab")
		)
		(fp_line
			(start 0.67945 -0.3048)
			(end 0.67945 0.3048)
			(stroke
				(width 0.1)
				(type default)
			)
			(layer "F.Fab")
		)
		(fp_line
			(start 0.67945 0.3048)
			(end 0.120396 0.3048)
			(stroke
				(width 0.1)
				(type default)
			)
			(layer "F.Fab")
		)
		(pad "1" smd circle
			(at -0.40005 0)
			(size 0 0)
			(layers "F.Cu" "F.Mask" "F.Paste")
			(net "SSD0_PWR_EN_R")
		)
		(pad "2" smd circle
			(at 0.40005 0)
			(size 0 0)
			(layers "F.Cu" "F.Mask" "F.Paste")
			(net "GND")
		)
	)
)
